# SCM (Grand Teton) — schematic parts with pin connectivity, parts 1361–1361 of 1428; source: Cadence DE-HDL packaged netlist (pstxprt.dat, pstxnet.dat, pstchip.dat)

U5  AST2600A3GP  AST2600A3-GP IC  pkg BGA624_0-8_21X21XA  page 12  (pins 1-324 of 624)
  A1  GND_A1  POWER  = GND
  A2  \rgmii1rxctl||gpio18a7\  BI  = NC
  A3  \rgmii1txd1||rmii1txd1||gpio18a3\  BI  = NC
  A4  USB2A_DP  BI  = USB_HOST_BMC_A_R_DP
  A5  GND_A5  POWER  = GND
  A6  USB2B_DP  BI  = USB_HOST_BMC_B_R_DP
  A7  \perst#\  IN  = RST_PLTRST_N
  A8  DDCDAT  OUT  = V_BMC_DDC_SDA
  A9  \tms||mtms1\  BI  = JTAG_SCM_TMS
  A10  RGMIICK  IN  = PD_CLK_125M_PHY_BMC_RGMII
  A11  \gpiok0||scl5\  BI  = SMB_BMC_MM5_R_SCL
  A12  \gpiom2||ndsr1\  BI  = PWRGD_PSU_AC_PWROK_BMC
  A13  \gpiol3||sda10\  BI  = SMB_BMC_MM10_R_SDA
  A14  \gpiol1||sda9\  BI  = SMB_BMC_MM9_R_SDA
  A15  \gpioi7||siosci#\  BI  = IRQ_PCH_SCI_WHEA_R_N
  A16  \gpioi1||mtdi2||rxd12\  BI  = JTAG_1_BMC_TDI_R
  A17  \gpioh3||sgpm1i\  BI  = SGPIO_BMC_M1_DI
  A18  \gpioh0||sgpm1ck\  BI  = SGPIO_BMC_M1_CLK
  A19  \gpioj5||hvi3c5sda||sda3\  BI  = SMB_BMC_MM3_R_SDA
  A20  \gpioj1||hvi3c3sda||sda1\  BI  = SMB_BMC_MM1_R_SDA
  A21  \gpiog4||txd8||sd2dat2||salt13\  BI  = BMC_EMMC_DT6
  A22  \gpiog3||rxd7||sd2dat1||salt12\  BI  = BMC_EMMC_DT5
  A23  \gpiof7||sd1wp#||pwm15\  BI  = BMC_EMMC_WP_N
  A24  \gpiof6||sd1cd#||pwm14\  BI  = BMC_EMMC_CD_N
  A25  \gpiof5||sd1dat3||pwm13\  BI  = BMC_EMMC_DT3
  A26  GND_A26  POWER  = GND
  AA1  GND_AA1  POWER  = GND
  AA2  DPTXN1  OUT  = NC_DP_BMC_TX1_N
  AA3  GND_AA3  POWER  = GND
  AA4  \gpio18d1||emmccmd\  BI  = NC
  AA5  \gpio18d3||emmcdat1\  BI  = NC
  AA6  GND_AA6  POWER  = GND
  AA7  GND_AA7  POWER  = GND
  AA8  GND_AA8  POWER  = GND
  AA9  \gpiox1||spi2cs1#\  BI  = PWRGD_DSW_PWROK_R1
  AA10  GND_AA10  POWER  = GND
  AA11  \gpioz5||spi1miso\  BI  = SPI_BMC_TPM_MISO_R1
  AA12  \gpioy3||salt8||wdtrst4#\  BI  = BMC_EMMC_RST_R_N
  AA13  \fwspics1#\  OUT  = SPI_BMC_BOOT_CS1_R1_N
  AA14  GND_AA14  POWER  = GND
  AA15  GND_AA15  POWER  = GND
  AA16  \adc13||gpiu5||salt14\  IN  = FM_BMC_EN_DET_R
  AA17  \adc9||gpiu1||salt10\  IN  = SMB_BMC_ALERT10_R_N
  AA18  PECIVDD  POWER  = PVCCIO_PECI_BMC
  AA19  GND_AA19  POWER  = GND
  AA20  GND_AA20  POWER  = GND
  AA21  ADCAV33_AA21  POWER  = A_BMC_ADCAV33
  AA22  GND_AA22  POWER  = GND
  AA23  \gpiop2||pwm10||thruin1\  BI  = ID_RST_BTN_BMC_R_N
  AA24  \gpiop3||pwm11||thruout1\  BI  = RST_BMC_RSTBTN_OUT_R_N
  AA25  \gpioq0||tach0\  BI  = IRQ_PCH_TPM_SPI_N
  AA26  \gpioq7||tach7\  BI  = FM_SOL_UART_CH_SEL_R1
  AB1  DPTXN0  OUT  = NC_DP_BMC_TX0_N
  AB2  DPTXP1  OUT  = NC_DP_BMC_TX1_P
  AB3  DPAUXN  BI  = NC_DP_BMC_AUX_N
  AB4  \gpio18d0||emmcclk\  BI  = NC
  AB5  \gpio18d5||emmcdat3\  BI  = NC
  AB6  \gpio18d7||emmcwp#\  BI  = NC
  AB7  \gpiow0||lad0||espid0\  BI  = ESPI_LPC_D0_IO0
  AB8  \gpiow1||lad1||espid1\  BI  = ESPI_LPC_D1_IO1
  AB9  \gpiox4||spi2mosi\  BI  = SPI_BMC_BIOS_ROM_MOSI
  AB10  \gpiox7||spi2dq3||rxd12\  BI  = SPI_BMC_BIOS_ROM_IO3
  AB11  \gpioz3||spi1ck\  BI  = SPI_BMC_TPM_CLK_R1
  AB12  \gpioy7||fwspiwp#\  BI  = PU_FWSPIWP_N_R
  AB13  FWSPIMISO  BI  = SPI_BMC_MISO_IO1_R
  AB14  \fwspics0#\  OUT  = SPI_BMC_BOOT_CS0_R1_N
  AB15  \gpiov0||sios3#\  BI  = FM_SLPS3_GF_R1_N
  AB16  \adc8||gpiu0||salt9\  IN  = SMB_BMC_ALERT9_R_N
  AB17  \adc10||gpiu2||salt11\  IN  = P1V0_SENSOR
  AB18  \adc6||gpit6\  IN  = P1V2_SENSOR
  AB19  \adc5||gpit5\  IN  = PGPPA_BMC_AUX_SENSOR
  AB20  ADCVREFN0  OUT  = A_BMC_ADCVREFN0
  AB21  \chasi#\  IN  = FM_INTRUDER_R_N
  AB22  \gpiop0||pwm8||thruin0\  BI  = FM_PWR_BTN
  AB23  \gpiop5||pwm13||thruout2\  BI  = H_CPU0_MEMTRIP_LVC1_N
  AB24  \gpiop6||pwm14\  BI  = H_CPU1_MEMTRIP_LVC1_N
  AB25  \gpioq1||tach1\  BI  = USB_OC0_REAR_R_N
  AB26  \gpioq3||tach3\  BI  = GPU_WP_HW_CTRL_R_N
  AC1  DPTXP0  OUT  = NC_DP_BMC_TX0_P
  AC2  GND_AC2  POWER  = GND
  AC3  DPAUXP  BI  = NC_DP_BMC_AUX_P
  AC4  \gpio18d2||emmcdat0\  BI  = NC
  AC5  \gpio18d6||emmccd#\  BI  = NC
  AC6  GND_AC6  POWER  = GND
  AC7  \gpiow3||lad3||espid3\  BI  = ESPI_LPC_D3_IO3
  AC8  \gpiow2||lad2||espid2\  BI  = ESPI_LPC_D2_IO2
  AC9  \gpiox2||spi2cs2#\  BI  = IRQ_SMI_ACTIVE_BMC_N
  AC10  \gpioz0||spi1cs1#\  BI  = SPI_BMC_TPM_CS2_R1_N
  AC11  \gpioz4||spi1mosi\  BI  = SPI_BMC_TPM_MOSI_R1
  AC12  \gpioy6||fwspiabr\  BI  = PU_BMC_FWSPIABR_N_R
  AC13  \fwspics2#\  OUT  = TP_BMC_SPICS2_N
  AC14  FWSPIMOSI  BI  = SPI_BMC_MOSI_IO0_R
  AC15  \gpiov3||sioonctrl#\  BI  = FM_BMC_ONCTL_R_N
  AC16  \adc12||gpiu4||salt13\  IN  = BSM_PRSNT_R_N
  AC17  \adc15||gpiu7||salt16\  IN  = SMB_BMC_ALERT16_N
  AC18  \adc1||gpit1\  IN  = P5V_SENSOR
  AC19  \adc4||gpit4\  IN  = P1V8_SENSOR
  AC20  ADCVREFP0  OUT  = A_BMC_ADCVREFP0
  AC21  DACRSET  BI  = A_BMC_DACREST
  AC22  \gpioo5||pwm5\  BI  = FM_TPM_PRSNT_0_N
  AC23  \gpioo7||pwm7\  BI  = FM_SPD_REMOTE_EN_R
  AC24  \gpioo6||pwm6\  BI  = FM_ADR_COMPLETE
  AC25  GND_AC25  POWER  = GND
  AC26  \gpioq5||tach5\  BI  = FM_P12V_HSC_ENABLE_R1
  AD1  GND_AD1  POWER  = GND
  AD2  RCRXP  IN  = P2E_GPU_RX_DP
  AD3  RCRXN  IN  = P2E_GPU_RX_DN
  AD4  GND_AD4  POWER  = GND
  AD5  PEREFCLKP  IN  = CLK_100M_PCH_DP
  AD6  PEREFCLKN  IN  = CLK_100M_PCH_DN
  AD7  \gpiow6||lsirq#||espialt#\  BI  = IRQ_ESPI_LPC_SERIRQ_ALERT0_N
  AD8  \gpiow7||lpcrst#||espirst#\  BI  = RST_ESPI_LPC_BMC_N
  AD9  \gpiox5||spi2miso\  BI  = SPI_BMC_BIOS_ROM_MISO
  AD10  \gpioz1||spi1abr\  BI  = PU_SPI1ABR
  AD11  \gpioz6||spi1dq2||txd13\  BI  = FM_DEBUG_PORT_PRSNT_R1_N
  AD12  \gpioy1||salt6||wdtrst2#\  BI  = RST_WDTRST_PLD_R1_N
  AD13  \spi1cs0#\  OUT  = TP_BMC_SPICS0_N
  AD14  \gpiov2||siopwreq#\  BI  = BMC_ID_BEEP_SEL_R1
  AD15  \gpiov6||lpcpme#\  BI  = FM_BMC_SUSACK_R1_N
  AD16  \adc14||gpiu6||salt15\  IN  = FM_PCHHOT_R_N
  AD17  ADCVREFP1  OUT  = A_BMC_ADCVREFP1
  AD18  ADCVREFN1  OUT  = A_BMC_ADCVREFN1
  AD19  \adc3||gpit3\  IN  = P2V5_SENSOR
  AD20  \adc0||gpit0\  IN  = P12V_SENSOR
  AD21  DACB  OUT  = V_DACB_R
  AD22  \gpioo1||pwm1\  BI  = NC
  AD23  \gpioo2||pwm2\  BI  = FM_PCIE_M2_SSD0_PRSNT_N
  AD24  \gpioo3||pwm3\  BI  = FM_JTAG_BMC_MUX_SEL_R1
  AD25  \gpioo4||pwm4\  BI  = FM_ADR_TRIGGER_N
  AD26  \gpioo0||pwm0\  BI  = FM_PMBUS_ALERT_EN
  AE1  RCREFCLKP  IN  = CLK_100M_GPU_DP
  AE2  RCREFCLKN  IN  = CLK_100M_GPU_DN
  AE3  GND_AE3  POWER  = GND
  AE4  PETXP  OUT  = P2E_PCH_TX_DP
  AE5  PETXN  OUT  = P2E_PCH_TX_DN
  AE6  GND_AE6  POWER  = GND
  AE7  \gpiow4||lclk||espick\  BI  = ESPI_HOST_LPC_BMC_CLK_R
  AE8  \gpiox0||spi2cs0#\  BI  = SPI_BMC_BIOS_CS0_R1_N
  AE9  GND_AE9  POWER  = GND
  AE10  \gpioz2||spi1wp#\  BI  = PU_SPI1WP_N
  AE11  \gpioy2||salt7||wdtrst3#\  BI  = FM_FLASH_LATCH_N_R1
  AE12  \gpioy4||fwspidq2\  BI  = SPI_BMC_IO2_R
  AE13  GND_AE13  POWER  = GND
  AE14  \gpiov5||lpcpd#\  BI  = FM_BMC_READY_R_PLD_N
  AE15  \gpiov4||siopwrgd\  BI  = BATTERY_DETECT
  AE16  \adc11||gpiu3||salt12\  IN  = SMB_BMC_ALERT12_N
  AE17  GND_AE17  POWER  = GND
  AE18  \adc7||gpit7\  IN  = P3V_BAT_SENSOR
  AE19  \adc2||gpit2\  IN  = P3V3_SENSOR
  AE20  GND_AE20  POWER  = GND
  AE21  DACG  OUT  = V_DACG_R
  AE22  I3C2SDA  BI  = I3C2_SDA_R
  AE23  GND_AE23  POWER  = GND
  AE24  I3C1SDA  BI  = I3C1_SDA_R
  AE25  \i3c4scl||fsi2clk\  BI  = I3C4_SCL_R
  AE26  \i3c3sda||fsi1data\  BI  = I3C3_SDA_R
  AF1  GND_AF1  POWER  = GND
  AF2  RCTXP  OUT  = P2E_GPU_TX_DN
  AF3  RCTXN  OUT  = P2E_GPU_TX_DP
  AF4  GND_AF4  POWER  = GND
  AF5  PERXP  IN  = P2E_PCH_RX_DP
  AF6  PERXN  IN  = P2E_PCH_RX_DN
  AF7  \gpiow5||lframe#||espics#\  BI  = ESPI_HOST_LPC_BMC_LFRAME_N_R
  AF8  \gpiox3||spi2ck\  BI  = SPI_BMC_BIOS_ROM_CLK
  AF9  \gpiox6||spi2dq2||txd12\  BI  = SPI_BMC_BIOS_ROM_IO2
  AF10  \gpioz7||spi1dq3||rxd13\  BI  = CLK_GEN2_BMC_RC_OE_N
  AF11  \gpioy0||salt5||wdtrst1#\  BI  = RST_BMC_SELF_HW_R1
  AF12  \gpioy5||fwspidq3\  BI  = SPI_BMC_IO3_R
  AF13  FWSPICK  OUT  = SPI_BMC_CLK_R
  AF14  \gpiov1||sios5#\  BI  = RST_RSMRST_R_N
  AF15  \gpiov7||lpcsmi#\  BI  = IRQ_TPM_SPI_N
  AF16  PECI  BI  = PECI_BMC_R
  AF17  ADCVREFEXT1  POWER  = ADCVREFEXT1
  AF18  ADCREXT1  OUT  = A_BMC_ADCREXT1
  AF19  ADCVREFEXT0  POWER  = ADCVREFEXT0
  AF20  ADCREXT0  OUT  = A_BMC_ADCREXT0
  AF21  DACR  OUT  = V_DACR_R
  AF22  I3C2SCL  BI  = I3C2_SCL_R
  AF23  I3C1SCL  BI  = I3C1_SCL_R
  AF24  \i3c4sda||fsi2data\  BI  = I3C4_SDA_R
  AF25  \i3c3scl||fsi1clk\  BI  = I3C3_SCL_R
  AF26  GND_AF26  POWER  = GND
  B1  \rgmii1rxd1||rmii1rxd1||gpio18b1\  BI  = NC
  B2  \rgmii1rxd0||rmii1rxd0||gpio18b0\  BI  = NC
  B3  \rgmii1rxck||rmii1rclki||gpio18a6\  BI  = NC
  B4  USB2A_DN  BI  = USB_HOST_BMC_A_R_DN
  B5  GND_B5  POWER  = GND
  B6  USB2B_DN  BI  = USB_HOST_BMC_B_R_DN
  B7  \rstind#\  OUT  = RST_SPI_FLASH_N
  B8  DDCCLK  OUT  = V_BMC_DDC_SCL
  B9  \tck||mtck1\  BI  = JTAG_SCM_TCK
  B10  \extrst#\  IN  = RST_EXTRST_N
  B11  GND_B11  POWER  = GND
  B12  \gpiom4||ndtr1\  BI  = PWRGD_SYS_PWROK_BMC
  B13  \gpiom1||ndcd1\  BI  = FM_VIRTUAL_RESEAT_BMC
  B14  \gpiol6||vgahs\  BI  = V_VGAHS_R
  B15  GND_B15  POWER  = GND
  B16  \gpioi6||siopbi#\  BI  = FM_THROTTLE_N
  B17  \gpioh5||sgps1ld||sda15\  BI  = SMB_BMC_MM15_R_SDA
  B18  \gpioh1||sgpm1ld\  BI  = SGPIO_BMC_M1_LD
  B19  GND_B19  POWER  = GND
  B20  \gpioj0||hvi3c3scl||scl1\  BI  = SMB_BMC_MM1_R_SCL
  B21  \gpiog7||rxd9||sd2wp#||salt16\  BI  = FM_BMC_DBP_PRESENT_R_N
  B22  \gpiog1||rxd6||sd2cmd||salt10\  BI  = UART_6_BMC_R_RXD
  B23  GND_B23  POWER  = GND
  B24  \rgmii4rxd3||rmii4rxer||nrts4||gpioe7\  BI  = RMII_RXER
  B25  \rgmii4rxd2||rmii4crsdv||ndtr4||gpioe6\  BI  = RMII_CSRDV
  B26  \rgmii4rxd1||rmii4rxd1||nri4||gpioe5\  BI  = RMII_RXD1
  C1  \rgmii2txd0||rmii2txd0||gpio18b6\  BI  = NC
  C2  \rgmii2txctl||rmii2txen||gpio18b5\  BI  = NC
  C3  GND_C3  POWER  = GND
  C4  \rgmii1rxd2||rmii1crsdv||gpio18b2\  BI  = NC
  C5  \rgmii1txd2||gpio18a4\  BI  = NC
  C6  \rgmii1txck||rmii1rclko||gpio18a0\  BI  = AC_PWR_BMC_BTN_R_N
  C7  DPHPD  IN  = DP_BMC_HPD_3V3_BUF
  C8  TXD5  OUT  = UART_BMC_5_TXD
  C9  \tdo||mtdo1\  BI  = JTAG_SCM_TDO
  C10  ENTEST  IN  = PD_SP_ENTEST
  C11  \gpiok1||sda5\  BI  = SMB_BMC_MM5_R_SDA
  C12  \gpiom5||nrts1\  BI  = FM_DBP_BMC_PRDY_R_N
  C13  \gpiom6||txd1\  BI  = UART_BMC_1_TXD
  C14  \gpiol7||vgavs\  BI  = V_VGAVS_R
  C15  \gpiol4||txd3\  BI  = FM_DBP_CPU_PREQ_GF_N
  C16  \gpioi4||mtdo2\  BI  = JTAG_1_BMC_TDO
  C17  \gpioh6||sgps1i0||scl16\  BI  = SMB_BMC_MM16_R_SCL
  C18  \gpioh2||sgpm1o\  BI  = SGPIO_BMC_M1_DO
  C19  \gpioj4||hvi3c5scl||scl3\  BI  = SMB_BMC_MM3_R_SCL
  C20  \gpioj6||hvi3c6scl||scl4\  BI  = SMB_BMC_MM4_R_SCL
  C21  \gpiog2||txd7||sd2dat0||salt11\  BI  = BMC_EMMC_DT4
  C22  \gpiof4||sd1dat2||pwm12\  BI  = BMC_EMMC_DT2
  C23  \gpiof3||sd1dat1||pwm11\  BI  = BMC_EMMC_DT1
  C24  \rgmii4rxd0||rmii4rxd0||ndsr4||gpioe4\  BI  = RMII_RXD0
  C25  \rgmii4rxck||rmii4rclki||ncts4||gpioe2\  BI  = RMII_OCP_RCLKI_R_ISO
  C26  \rgmii4rxctl||ndcd4||gpioe3\  BI  = FM_PLT_BMC_THERMTRIP_N_R
  D1  \rgmii2rxd0||rmii2rxd0||gpio18c4\  BI  = NC
  D2  \rgmii2rxck||rmii2rclki||gpio18c2\  BI  = NC
  D3  \rgmii2txd1||rmii2txd1||gpio18b7\  BI  = FM_BOARD_BMC_REV_ID0
  D4  \rgmii2txck||rmii2rclko||gpio18b4\  BI  = NC
  D5  \rgmii1txd0||rmii1txd0||gpio18a2\  BI  = NC
  D6  \rgmii1txctl||rmii1txen||gpio18a1\  BI  = NC
  D7  \ssprst#\  IN  = FM_BMC_SSPRST_N
  D8  RXD5  IN  = UART_BMC_5_RXD
  D9  \tdi||mtdi1\  BI  = JTAG_SCM_TDI
  D10  CLKIN  IN  = BMC_CLK_25M
  D11  \gpiok4||scl7\  BI  = SMB_BMC_MM7_R_SCL
  D12  \gpiok2||scl6\  BI  = SMB_BMC_MM6_R_SCL
  D13  \gpiom7||rxd1\  BI  = UART_BMC_1_RXD
  D14  \gpiom0||ncts1\  BI  = H_CPU0_PROCHOT_LVC1_N
  D15  \gpiol0||scl9\  BI  = SMB_BMC_MM9_R_SCL
  D16  \gpioi3||mtms2||rxd13\  BI  = JTAG_1_BMC_TMS_R
  D17  \gpioi0||mntrst2||txd12\  BI  = JTAG_1_BMC_TRST_R
  D18  \gpioh4||sgps1ck||scl15\  BI  = SMB_BMC_MM15_R_SCL
  D19  \gpioj7||hvi3c6sda||sda4\  BI  = SMB_BMC_MM4_R_SDA
  D20  \gpioj3||hvi3c4sda||sda2\  BI  = SMB_BMC_MM2_R_SDA
  D21  \gpiog6||txd9||sd2cd#||salt15\  BI  = SMB_BMC_ALERT15_N
  D22  \gpiof0||sd1clk||pwm8\  BI  = BMC_EMMC_CLK
  D23  \gpiof2||sd1dat0||pwm10\  BI  = BMC_EMMC_DT0
  D24  \rgmii4txd3||nrts3||gpioe1\  BI  = FM_BIOS_DEBUG_EN_R_N
  D25  GND_D25  POWER  = GND
  D26  \rgmii4txd2||ndtr3||gpioe0\  BI  = PD_BIOS_MUX_EN_R_N
  E1  \rgmii2rxd3||rmii2rxer||gpio18c7\  BI  = NC
  E2  \rgmii2rxd2||rmii2crsdv||gpio18c6\  BI  = NC
  E3  \rgmii2rxctl||gpio18c3\  BI  = NC
  E4  \rgmii2txd2||gpio18c0\  BI  = FM_BOARD_BMC_REV_ID1
  E5  \rgmii1rxd3||rmii1rxer||gpio18b3\  BI  = NC
  E6  \rgmii1txd3||gpio18a5\  BI  = NC
  E7  PLLAVDD_E7  POWER  = P1V0_STBY_PLAVDD
  E8  GND_E8  POWER  = GND
  E9  PLLDVDD_E9  POWER  = P1V0_STBY_PLAVDD
  E10  \srst#\  IN  = RST_BMC_SRST_N
  E11  \gpiok5||sda7\  BI  = SMB_BMC_MM7_R_SDA
  E12  \gpiok7||sda8\  BI  = SMB_BMC_MM8_R_SDA
  E13  \gpiok3||sda6\  BI  = SMB_BMC_MM6_R_SDA
  E14  \gpiom3||nri1\  BI  = FM_PECI_SEL_R_N
  E15  \gpiol2||scl10\  BI  = SMB_BMC_MM10_R_SCL
  E16  \gpioi5||siopbo#\  BI  = FLASH_WP_STATUS_R1
  E17  \gpioi2||mtck2||txd13\  BI  = JTAG_1_BMC_TCK_R
  E18  \gpioh7||sgps1i1||sda16\  BI  = SMB_BMC_MM16_R_SDA
  E19  \gpioj2||hvi3c4scl||scl2\  BI  = SMB_BMC_MM2_R_SCL
  E20  \gpiog5||rxd8||sd2dat3||salt14\  BI  = BMC_EMMC_DT7
  E21  \gpiog0||txd6||sd2clk||salt9\  BI  = UART_6_BMC_R_TXD
  E22  \gpiof1||sd1cmd||pwm9\  BI  = BMC_EMMC_CMD
  E23  \rgmii4txctl||rmii4txen||ndcd3||gpiod5\  BI  = RMII_TXEN_R
  E24  \rgmii4txd0||rmii4txd0||ndsr3||gpiod6\  BI  = RMII_TXD0_R
  E25  \rgmii4txd1||rmii4txd1||nri3||gpiod7\  BI  = RMII_TXD1_R
  E26  \rgmii3rxd3||rmii3rxer||gpiod3\  BI  = FM_BMC_CRASHLOG_TRIG_R1_N
  F1  MA2  OUT  = M_BMC_DDR4_MA<2>
  F2  MA10  OUT  = M_BMC_DDR4_MA<10>
  F3  MA0  OUT  = M_BMC_DDR4_MA<0>
  F4  \rgmii2rxd1||rmii2rxd1||gpio18c5\  BI  = NC
  F5  \rgmii2txd3||gpio18c1\  BI  = FM_BOARD_BMC_REV_ID2
  F6  GND_F6  POWER  = GND
  F7  PLLAVDD_F7  POWER  = P1V0_STBY_PLAVDD
  F8  GND_F8  POWER  = GND
  F9  PLLDVDD_F9  POWER  = P1V0_STBY_PLAVDD
  F10  GND_F10  POWER  = GND
  F11  \ntrst||mntrst1\  BI  = JTAG_SCM_NTRST
  F12  GND_F12  POWER  = GND
  F13  \gpiok6||scl8\  BI  = SMB_BMC_MM8_R_SCL
  F14  GND_F14  POWER  = GND
  F15  \gpiol5||rxd3\  BI  = FM_JTAG_TCK_MUX_BMC_SEL_R1
  F16  GND_F16  POWER  = GND
  F17  GND_F17  POWER  = GND
  F18  GND_F18  POWER  = GND
  F19  I3CVDDH_F19  POWER  = P3V3_P1V8_I2C_I3C
  F20  I3CVDDH_F20  POWER  = P3V3_P1V8_I2C_I3C
  F21  GND_F21  POWER  = GND
  F22  \rgmii3txd3||gpioc5\  BI  = H_CPU_CATERR_LVC2_R2_N
  F23  \rgmii3rxd0||rmii3rxd0||gpiod0\  BI  = GPU_FPGA_RST_N
  F24  \rgmii4txck||rmii4rclko||ncts3||gpiod4\  BI  = IRQ_SML0_ALERT_R_N
  F25  \rgmii3rxd2||rmii3crsdv||gpiod2\  BI  = FM_BIC_DEBUG_SW_N_R
  F26  \rgmii3rxd1||rmii3rxd1||gpiod1\  BI  = CLK_BUF1_GPU_FPGA_OE_R_N
  G1  MA11  OUT  = M_BMC_DDR4_MA<11>
  G2  GND_G2  POWER  = GND
  G3  \mba2||mbg0\  OUT  = M_BMC_DDR4_MBG0
  G4  MBA0  OUT  = M_BMC_DDR4_MBA0
  G5  \mwe#\  OUT  = M_BMC_DDR4_MWE_N
  G6  MVDD_G6  POWER  = P1V2_AUX
  G21  SD1VDD_G21  POWER  = P3V3_P1V8_SD1VDD
  G22  \rgmii3txd2||gpioc4\  BI  = RST_ROT_CPU_R1_N
  G23  \rgmii3rxck||rmii3rclki||gpioc6\  BI  = FM_JTAG_SEL
  G24  \rgmii3rxctl||gpioc7\  BI  = IRQ_SGPIO_BMC_N
  G25  GND_G25  POWER  = GND
  G26  \gpiob5||mdio2\  BI  = FM_ID_LED
